# S9S_MB_2U (Grand Teton) — schematic netlist excerpt (pin names and nets, part order shuffled) for the footprints in the layout excerpt that follows; sources: Cadence DE-HDL packaged netlist, KiCad conversion of 03242023_DA0F0TMBIJ0_F0T_Motherboard_J_brd_V01_OCP.brd

R4124  Q_RES  100K 1% EMPTY  pkg 0402LF  page 146 : A = GPU_3V3IO_RSVD1_FFU ; B = GND
PC294_P0_2  Q_CAP  2.2UF 10V 10% X6S  pkg C0402  page 267 : A = PVCCIN_CPU0_PVCC ; B = GND

(kicad_pcb
	(version 20260206)
	(generator "pcbnew")
	(generator_version "10.0")
	(general
		(thickness 1.6)
		(legacy_teardrops no)
	)
	(paper "A4")
	(title_block
		(title "03242023_DA0F0TMBIJ0_F0T_Motherboard_J_brd_V01_OCP.brd")
		(comment 1 "Grand Teton / footprints 1679-1680 of 6105")
	)
	(layers
		(0 "F.Cu" signal "TOP")
		(4 "In1.Cu" signal "GND")
		(6 "In2.Cu" signal "IN1")
		(8 "In3.Cu" signal "GND1")
		(10 "In4.Cu" signal "IN2")
		(12 "In5.Cu" signal "GND2")
		(14 "In6.Cu" signal "IN3")
		(16 "In7.Cu" signal "GND3")
		(18 "In8.Cu" signal "VCC")
		(20 "In9.Cu" signal "VCC1")
		(22 "In10.Cu" signal "GND4")
		(24 "In11.Cu" signal "IN4")
		(26 "In12.Cu" signal "GND5")
		(28 "In13.Cu" signal "IN5")
		(30 "In14.Cu" signal "GND6")
		(32 "In15.Cu" signal "IN6")
		(34 "In16.Cu" signal "GND7")
		(2 "B.Cu" signal "BOTTOM")
		(9 "F.Adhes" user "F.Adhesive")
		(11 "B.Adhes" user "B.Adhesive")
		(13 "F.Paste" user "Package Geometry/Pastemask Top")
		(15 "B.Paste" user "Package Geometry/Pastemask Bottom")
		(5 "F.SilkS" user "Ref Des/Silkscreen Top")
		(7 "B.SilkS" user "Ref Des/Silkscreen Bottom")
		(1 "F.Mask" user "Board Geometry/Soldermask Top")
		(3 "B.Mask" user "Board Geometry/Soldermask Bottom")
		(17 "Dwgs.User" user "User.Drawings")
		(19 "Cmts.User" user "User.Comments")
		(21 "Eco1.User" user "User.Eco1")
		(23 "Eco2.User" user "User.Eco2")
		(25 "Edge.Cuts" user "Board Geometry/Outline")
		(27 "Margin" user)
		(31 "F.CrtYd" user "Package Geometry/Place Bound Top")
		(29 "B.CrtYd" user "Package Geometry/Place Bound Bottom")
		(35 "F.Fab" user "Ref Des/Assembly Top")
		(33 "B.Fab" user "Ref Des/Assembly Bottom")
	)
	(footprint ""
		(layer "F.Cu")
		(at 308.33314 -430.73701 -90)
		(property "Reference" "R4124"
			(at 0 0 270)
			(layer "F.SilkS")
			(hide yes)
			(effects
				(font
					(size 1.27 1.27)
				)
			)
		)
		(property "Value" ""
			(at 0 0 270)
			(layer "F.Fab")
			(effects
				(font
					(size 1.27 1.27)
				)
			)
		)
		(duplicate_pad_numbers_are_jumpers no)
		(fp_line
			(start -0.7874 0.4064)
			(end -0.7874 -0.4064)
			(stroke
				(width 0.1524)
				(type default)
			)
			(layer "F.SilkS")
		)
		(fp_line
			(start 0.7874 0.4064)
			(end -0.7874 0.4064)
			(stroke
				(width 0.1524)
				(type default)
			)
			(layer "F.SilkS")
		)
		(fp_line
			(start -0.7874 -0.4064)
			(end 0.7874 -0.4064)
			(stroke
				(width 0.1524)
				(type default)
			)
			(layer "F.SilkS")
		)
		(fp_line
			(start 0.7874 -0.4064)
			(end 0.7874 0.4064)
			(stroke
				(width 0.1524)
				(type default)
			)
			(layer "F.SilkS")
		)
		(fp_line
			(start -0.67945 0.3048)
			(end -0.67945 -0.305054)
			(stroke
				(width 0.1)
				(type default)
			)
			(layer "F.Fab")
		)
		(fp_line
			(start -0.12065 0.3048)
			(end -0.67945 0.3048)
			(stroke
				(width 0.1)
				(type default)
			)
			(layer "F.Fab")
		)
		(fp_line
			(start 0.120396 0.3048)
			(end 0.120396 0.2794)
			(stroke
				(width 0.1)
				(type default)
			)
			(layer "F.Fab")
		)
		(fp_line
			(start 0.67945 0.3048)
			(end 0.120396 0.3048)
			(stroke
				(width 0.1)
				(type default)
			)
			(layer "F.Fab")
		)
		(fp_line
			(start -0.12065 0.2794)
			(end -0.12065 0.3048)
			(stroke
				(width 0.1)
				(type default)
			)
			(layer "F.Fab")
		)
		(fp_line
			(start 0.120396 0.2794)
			(end -0.12065 0.2794)
			(stroke
				(width 0.1)
				(type default)
			)
			(layer "F.Fab")
		)
		(fp_line
			(start -0.12065 -0.2794)
			(end 0.12065 -0.2794)
			(stroke
				(width 0.1)
				(type default)
			)
			(layer "F.Fab")
		)
		(fp_line
			(start 0.12065 -0.2794)
			(end 0.12065 -0.3048)
			(stroke
				(width 0.1)
				(type default)
			)
			(layer "F.Fab")
		)
		(fp_line
			(start 0.12065 -0.3048)
			(end 0.67945 -0.3048)
			(stroke
				(width 0.1)
				(type default)
			)
			(layer "F.Fab")
		)
		(fp_line
			(start 0.67945 -0.3048)
			(end 0.67945 0.3048)
			(stroke
				(width 0.1)
				(type default)
			)
			(layer "F.Fab")
		)
		(fp_line
			(start -0.67945 -0.305054)
			(end -0.12065 -0.305054)
			(stroke
				(width 0.1)
				(type default)
			)
			(layer "F.Fab")
		)
		(fp_line
			(start -0.12065 -0.305054)
			(end -0.12065 -0.2794)
			(stroke
				(width 0.1)
				(type default)
			)
			(layer "F.Fab")
		)
		(pad "1" smd circle
			(at -0.40005 0 270)
			(size 0 0)
			(layers "F.Cu" "F.Mask" "F.Paste")
			(net "GPU_3V3IO_RSVD1_FFU")
		)
		(pad "2" smd circle
			(at 0.40005 0 270)
			(size 0 0)
			(layers "F.Cu" "F.Mask" "F.Paste")
			(net "GND")
		)
	)
	(footprint ""
		(layer "F.Cu")
		(at 349.523304 -333.525368 -90)
		(property "Reference" "PC294_P0_2"
			(at 0 0 270)
			(layer "F.SilkS")
			(hide yes)
			(effects
				(font
					(size 1.27 1.27)
				)
			)
		)
		(property "Value" ""
			(at 0 0 270)
			(layer "F.Fab")
			(effects
				(font
					(size 1.27 1.27)
				)
			)
		)
		(duplicate_pad_numbers_are_jumpers no)
		(fp_line
			(start -0.7874 0.4064)
			(end -0.7874 -0.4064)
			(stroke
				(width 0.1524)
				(type default)
			)
			(layer "F.SilkS")
		)
		(fp_line
			(start 0.7874 0.4064)
			(end -0.7874 0.4064)
			(stroke
				(width 0.1524)
				(type default)
			)
			(layer "F.SilkS")
		)
		(fp_line
			(start -0.7874 -0.4064)
			(end 0.7874 -0.4064)
			(stroke
				(width 0.1524)
				(type default)
			)
			(layer "F.SilkS")
		)
		(fp_line
			(start 0.7874 -0.4064)
			(end 0.7874 0.4064)
			(stroke
				(width 0.1524)
				(type default)
			)
			(layer "F.SilkS")
		)
		(fp_line
			(start -0.67945 0.3048)
			(end -0.67945 -0.305054)
			(stroke
				(width 0.1)
				(type default)
			)
			(layer "F.Fab")
		)
		(fp_line
			(start -0.12065 0.3048)
			(end -0.67945 0.3048)
			(stroke
				(width 0.1)
				(type default)
			)
			(layer "F.Fab")
		)
		(fp_line
			(start 0.120396 0.3048)
			(end 0.120396 0.2794)
			(stroke
				(width 0.1)
				(type default)
			)
			(layer "F.Fab")
		)
		(fp_line
			(start 0.67945 0.3048)
			(end 0.120396 0.3048)
			(stroke
				(width 0.1)
				(type default)
			)
			(layer "F.Fab")
		)
		(fp_line
			(start -0.12065 0.2794)
			(end -0.12065 0.3048)
			(stroke
				(width 0.1)
				(type default)
			)
			(layer "F.Fab")
		)
		(fp_line
			(start 0.120396 0.2794)
			(end -0.12065 0.2794)
			(stroke
				(width 0.1)
				(type default)
			)
			(layer "F.Fab")
		)
		(fp_line
			(start -0.12065 -0.2794)
			(end 0.12065 -0.2794)
			(stroke
				(width 0.1)
				(type default)
			)
			(layer "F.Fab")
		)
		(fp_line
			(start 0.12065 -0.2794)
			(end 0.12065 -0.3048)
			(stroke
				(width 0.1)
				(type default)
			)
			(layer "F.Fab")
		)
		(fp_line
			(start 0.12065 -0.3048)
			(end 0.67945 -0.3048)
			(stroke
				(width 0.1)
				(type default)
			)
			(layer "F.Fab")
		)
		(fp_line
			(start 0.67945 -0.3048)
			(end 0.67945 0.3048)
			(stroke
				(width 0.1)
				(type default)
			)
			(layer "F.Fab")
		)
		(fp_line
			(start -0.67945 -0.305054)
			(end -0.12065 -0.305054)
			(stroke
				(width 0.1)
				(type default)
			)
			(layer "F.Fab")
		)
		(fp_line
			(start -0.12065 -0.305054)
			(end -0.12065 -0.2794)
			(stroke
				(width 0.1)
				(type default)
			)
			(layer "F.Fab")
		)
		(pad "1" smd circle
			(at -0.40005 0 270)
			(size 0 0)
			(layers "F.Cu" "F.Mask" "F.Paste")
			(net "PVCCIN_CPU0_PVCC")
		)
		(pad "2" smd circle
			(at 0.40005 0 270)
			(size 0 0)
			(layers "F.Cu" "F.Mask" "F.Paste")
			(net "GND")
		)
	)
)
